# S9S_MB_2U (Grand Teton) — schematic netlist excerpt (pin names and nets, part order shuffled) for the footprints in the layout excerpt that follows; sources: Cadence DE-HDL packaged netlist, KiCad conversion of 03242023_DA0F0TMBIJ0_F0T_Motherboard_J_brd_V01_OCP.brd

C1664  Q_CAP  0.1UF 25V 10% X7R  pkg 0402  page 239 : A = P0V7_JTAG_VREF_2 ; B = GND
C1014  Q_CAP  22UF 4V 20% X6S  pkg C0402  page 74 : A = PVCCIN_CPU0 ; B = GND

(kicad_pcb
	(version 20260206)
	(generator "pcbnew")
	(generator_version "10.0")
	(general
		(thickness 1.6)
		(legacy_teardrops no)
	)
	(paper "A4")
	(title_block
		(title "03242023_DA0F0TMBIJ0_F0T_Motherboard_J_brd_V01_OCP.brd")
		(comment 1 "Grand Teton / footprints 2177-2178 of 6105")
	)
	(layers
		(0 "F.Cu" signal "TOP")
		(4 "In1.Cu" signal "GND")
		(6 "In2.Cu" signal "IN1")
		(8 "In3.Cu" signal "GND1")
		(10 "In4.Cu" signal "IN2")
		(12 "In5.Cu" signal "GND2")
		(14 "In6.Cu" signal "IN3")
		(16 "In7.Cu" signal "GND3")
		(18 "In8.Cu" signal "VCC")
		(20 "In9.Cu" signal "VCC1")
		(22 "In10.Cu" signal "GND4")
		(24 "In11.Cu" signal "IN4")
		(26 "In12.Cu" signal "GND5")
		(28 "In13.Cu" signal "IN5")
		(30 "In14.Cu" signal "GND6")
		(32 "In15.Cu" signal "IN6")
		(34 "In16.Cu" signal "GND7")
		(2 "B.Cu" signal "BOTTOM")
		(9 "F.Adhes" user "F.Adhesive")
		(11 "B.Adhes" user "B.Adhesive")
		(13 "F.Paste" user "Package Geometry/Pastemask Top")
		(15 "B.Paste" user "Package Geometry/Pastemask Bottom")
		(5 "F.SilkS" user "Ref Des/Silkscreen Top")
		(7 "B.SilkS" user "Ref Des/Silkscreen Bottom")
		(1 "F.Mask" user "Board Geometry/Soldermask Top")
		(3 "B.Mask" user "Board Geometry/Soldermask Bottom")
		(17 "Dwgs.User" user "User.Drawings")
		(19 "Cmts.User" user "User.Comments")
		(21 "Eco1.User" user "User.Eco1")
		(23 "Eco2.User" user "User.Eco2")
		(25 "Edge.Cuts" user "Board Geometry/Outline")
		(27 "Margin" user)
		(31 "F.CrtYd" user "Package Geometry/Place Bound Top")
		(29 "B.CrtYd" user "Package Geometry/Place Bound Bottom")
		(35 "F.Fab" user "Ref Des/Assembly Top")
		(33 "B.Fab" user "Ref Des/Assembly Bottom")
	)
	(footprint ""
		(layer "F.Cu")
		(at 378.5616 -107.183428)
		(property "Reference" "C1664"
			(at 0 0 0)
			(layer "F.SilkS")
			(hide yes)
			(effects
				(font
					(size 1.27 1.27)
				)
			)
		)
		(property "Value" ""
			(at 0 0 0)
			(layer "F.Fab")
			(effects
				(font
					(size 1.27 1.27)
				)
			)
		)
		(duplicate_pad_numbers_are_jumpers no)
		(fp_line
			(start -0.7874 -0.4064)
			(end 0.7874 -0.4064)
			(stroke
				(width 0.1524)
				(type default)
			)
			(layer "F.SilkS")
		)
		(fp_line
			(start -0.7874 0.4064)
			(end -0.7874 -0.4064)
			(stroke
				(width 0.1524)
				(type default)
			)
			(layer "F.SilkS")
		)
		(fp_line
			(start 0.7874 -0.4064)
			(end 0.7874 0.4064)
			(stroke
				(width 0.1524)
				(type default)
			)
			(layer "F.SilkS")
		)
		(fp_line
			(start 0.7874 0.4064)
			(end -0.7874 0.4064)
			(stroke
				(width 0.1524)
				(type default)
			)
			(layer "F.SilkS")
		)
		(fp_line
			(start -0.67945 -0.305054)
			(end -0.12065 -0.305054)
			(stroke
				(width 0.1)
				(type default)
			)
			(layer "F.Fab")
		)
		(fp_line
			(start -0.67945 0.3048)
			(end -0.67945 -0.305054)
			(stroke
				(width 0.1)
				(type default)
			)
			(layer "F.Fab")
		)
		(fp_line
			(start -0.12065 -0.305054)
			(end -0.12065 -0.2794)
			(stroke
				(width 0.1)
				(type default)
			)
			(layer "F.Fab")
		)
		(fp_line
			(start -0.12065 -0.2794)
			(end 0.12065 -0.2794)
			(stroke
				(width 0.1)
				(type default)
			)
			(layer "F.Fab")
		)
		(fp_line
			(start -0.12065 0.2794)
			(end -0.12065 0.3048)
			(stroke
				(width 0.1)
				(type default)
			)
			(layer "F.Fab")
		)
		(fp_line
			(start -0.12065 0.3048)
			(end -0.67945 0.3048)
			(stroke
				(width 0.1)
				(type default)
			)
			(layer "F.Fab")
		)
		(fp_line
			(start 0.120396 0.2794)
			(end -0.12065 0.2794)
			(stroke
				(width 0.1)
				(type default)
			)
			(layer "F.Fab")
		)
		(fp_line
			(start 0.120396 0.3048)
			(end 0.120396 0.2794)
			(stroke
				(width 0.1)
				(type default)
			)
			(layer "F.Fab")
		)
		(fp_line
			(start 0.12065 -0.3048)
			(end 0.67945 -0.3048)
			(stroke
				(width 0.1)
				(type default)
			)
			(layer "F.Fab")
		)
		(fp_line
			(start 0.12065 -0.2794)
			(end 0.12065 -0.3048)
			(stroke
				(width 0.1)
				(type default)
			)
			(layer "F.Fab")
		)
		(fp_line
			(start 0.67945 -0.3048)
			(end 0.67945 0.3048)
			(stroke
				(width 0.1)
				(type default)
			)
			(layer "F.Fab")
		)
		(fp_line
			(start 0.67945 0.3048)
			(end 0.120396 0.3048)
			(stroke
				(width 0.1)
				(type default)
			)
			(layer "F.Fab")
		)
		(pad "1" smd circle
			(at -0.40005 0)
			(size 0 0)
			(layers "F.Cu" "F.Mask" "F.Paste")
			(net "P0V7_JTAG_VREF_2")
		)
		(pad "2" smd circle
			(at 0.40005 0)
			(size 0 0)
			(layers "F.Cu" "F.Mask" "F.Paste")
			(net "GND")
		)
	)
	(footprint ""
		(layer "F.Cu")
		(at 352.283014 -251.375418 90)
		(property "Reference" "C1014"
			(at 0 0 90)
			(layer "F.SilkS")
			(hide yes)
			(effects
				(font
					(size 1.27 1.27)
				)
			)
		)
		(property "Value" ""
			(at 0 0 90)
			(layer "F.Fab")
			(effects
				(font
					(size 1.27 1.27)
				)
			)
		)
		(duplicate_pad_numbers_are_jumpers no)
		(fp_line
			(start 0.7874 -0.4064)
			(end 0.7874 0.4064)
			(stroke
				(width 0.1524)
				(type default)
			)
			(layer "F.SilkS")
		)
		(fp_line
			(start -0.7874 -0.4064)
			(end 0.7874 -0.4064)
			(stroke
				(width 0.1524)
				(type default)
			)
			(layer "F.SilkS")
		)
		(fp_line
			(start 0.7874 0.4064)
			(end -0.7874 0.4064)
			(stroke
				(width 0.1524)
				(type default)
			)
			(layer "F.SilkS")
		)
		(fp_line
			(start -0.7874 0.4064)
			(end -0.7874 -0.4064)
			(stroke
				(width 0.1524)
				(type default)
			)
			(layer "F.SilkS")
		)
		(fp_line
			(start -0.12065 -0.305054)
			(end -0.12065 -0.2794)
			(stroke
				(width 0.1)
				(type default)
			)
			(layer "F.Fab")
		)
		(fp_line
			(start -0.67945 -0.305054)
			(end -0.12065 -0.305054)
			(stroke
				(width 0.1)
				(type default)
			)
			(layer "F.Fab")
		)
		(fp_line
			(start 0.67945 -0.3048)
			(end 0.67945 0.3048)
			(stroke
				(width 0.1)
				(type default)
			)
			(layer "F.Fab")
		)
		(fp_line
			(start 0.12065 -0.3048)
			(end 0.67945 -0.3048)
			(stroke
				(width 0.1)
				(type default)
			)
			(layer "F.Fab")
		)
		(fp_line
			(start 0.12065 -0.2794)
			(end 0.12065 -0.3048)
			(stroke
				(width 0.1)
				(type default)
			)
			(layer "F.Fab")
		)
		(fp_line
			(start -0.12065 -0.2794)
			(end 0.12065 -0.2794)
			(stroke
				(width 0.1)
				(type default)
			)
			(layer "F.Fab")
		)
		(fp_line
			(start 0.120396 0.2794)
			(end -0.12065 0.2794)
			(stroke
				(width 0.1)
				(type default)
			)
			(layer "F.Fab")
		)
		(fp_line
			(start -0.12065 0.2794)
			(end -0.12065 0.3048)
			(stroke
				(width 0.1)
				(type default)
			)
			(layer "F.Fab")
		)
		(fp_line
			(start 0.67945 0.3048)
			(end 0.120396 0.3048)
			(stroke
				(width 0.1)
				(type default)
			)
			(layer "F.Fab")
		)
		(fp_line
			(start 0.120396 0.3048)
			(end 0.120396 0.2794)
			(stroke
				(width 0.1)
				(type default)
			)
			(layer "F.Fab")
		)
		(fp_line
			(start -0.12065 0.3048)
			(end -0.67945 0.3048)
			(stroke
				(width 0.1)
				(type default)
			)
			(layer "F.Fab")
		)
		(fp_line
			(start -0.67945 0.3048)
			(end -0.67945 -0.305054)
			(stroke
				(width 0.1)
				(type default)
			)
			(layer "F.Fab")
		)
		(pad "1" smd circle
			(at -0.40005 0 90)
			(size 0 0)
			(layers "F.Cu" "F.Mask" "F.Paste")
			(net "PVCCIN_CPU0")
		)
		(pad "2" smd circle
			(at 0.40005 0 90)
			(size 0 0)
			(layers "F.Cu" "F.Mask" "F.Paste")
			(net "GND")
		)
	)
)
